FILE_TYPE = CONNECTIVITY;
{Allegro Design Entry HDL 17.2-2016 S081 (4005846) 1/11/2022}
"PAGE_NUMBER" = 272;
0"NC";
1"PVCCIN_CPU1_PVCC\g";
2"PVCCIN_CPU1_PVCC\g";
3"SW_P12V_PVCCIN_CPU1_FLT\g";
4"SW_P12V_PVCCIN_CPU1_FLT\g";
5"PVCCIN_CPU1\g";
6"PVCCIN_CPU1\g";
7"GND\g";
8"GND\g";
9"GND\g";
10"GND\g";
11"GND\g";
12"GND\g";
13"GND\g";
14"GND\g";
15"GND\g";
16"GND\g";
17"GND\g";
18"GND\g";
19"GND\g";
20"GND\g";
21"PVCCIN_CPU1_LSET4";
22"PVCCIN_CPU1_PWM4";
23"PVCCIN_CPU1_ATSEN";
24"PVCCIN_CPU1_IMON4";
25"PVCCIN_CPU1_VREF"CDS_PHYS_NET_NAME"PVCCIN_CPU1_VREF";
26"PVCCIN_CPU1_VDD4";
27"PVCCIN_CPU1_PWM3";
28"PVCCIN_CPU1_ATSEN";
29"PVCCIN_CPU1_LSET3";
30"PVCCIN_CPU1_IMON3";
31"PVCCIN_CPU1_VDD3";
32"PVCCIN_CPU1_VOS4";
33"SW_PVCCIN_CPU1_BOOT4"CDS_PHYS_NET_NAME"SW_PVCCIN_CPU1_BOOT4";
34"SW_PVCCIN_CPU1_BOOT4_R";
35"SW_PVCCIN_CPU1_BOOTR4"CDS_PHYS_NET_NAME"SW_PVCCIN_CPU1_BOOTR4";
36"IND_P1_CPL4";
37"SW_PVCCIN_CPU1_SW4";
38"IND_P1_CPL3";
39"PVCCIN_CPU1_VOS3";
40"SW_PVCCIN_CPU1_BOOT3"CDS_PHYS_NET_NAME"SW_PVCCIN_CPU1_BOOT3";
41"SW_PVCCIN_CPU1_BOOT3_R";
42"IND_P1_CPL3";
43"SW_PVCCIN_CPU1_BOOTR3"CDS_PHYS_NET_NAME"SW_PVCCIN_CPU1_BOOTR3";
44"SW_PVCCIN_CPU1_SW3";
45"IND_P1_CPL2";
46"PVCCIN_CPU1_VREF"CDS_PHYS_NET_NAME"PVCCIN_CPU1_VREF";
%"UNIVERSAL_GND"
"1","(-2775,-2275)","0","logical_power","I1";
;
HDL_POWER"GND"
CDS_LIB"logical_power";
"A"7;
%"ISL99390FRZTR5935"
"1","(-850,-1550)","0","pure_quanta","I10";
;
PART_NUMBER"AL099390004"
VALUE"ISL99390FRZ-TR5935"
MATERIAL"IC"
PART_TYPE"SMLF"
LOCATION"PU27_P1_4"
NEEDS_NO_SIZE"TRUE"
CDS_LMAN_SYM_OUTLINE"-300,700,250,-650"
CDS_LIB"pure_quanta"
SEC_TYPE""
SEC"1";
"PGND2"
$PN"7_9-20_24"15;
"GL2"
$PN"41"0;
"GL1"
$PN"6"0;
"DNC"
$PN"31"0;
"EN"
$PN"35"26;
"PGND3"
$PN"40"15;
"VOS"
$PN"1"32;
"VIN2"
$PN"30"3;
"PGND1"
$PN"5"15;
"SW"
$PN"10_19"37;
"LSET"
$PN"37"21;
"IOUT"
$PN"38"24;
"TOUT_FLT"
$PN"36"23;
"PVCC"
$PN"4"1;
"PHASE"
$PN"32"35;
"VIN1"
$PN"25_29"3;
"BOOT"
$PN"33"33;
"AGND"
$PN"2"15;
"VCC"
$PN"3"26;
"REFIN"
$PN"39"25;
"PWM"
$PN"34"22;
%"Q_CAP"
"1","(-2375,-1050)","0","pure_quanta","I11";
;
PART_NUMBER"CH5222KEB01"
PACK_TYPE"C0402"
VOLTAGE"10V"
VALUE"2.2UF"
TOLERANCE"10%"
MATERIAL"X6S"
LOCATION"PC523"
CDS_LIB"pure_quanta"
LOCATION"PC523"
$SEC"1"
CDS_SEC"1";
"B"
$PN"2"9;
"A"
$PN"1"26;
%"Q_RES"
"2","(-2375,-550)","0","pure_quanta","I12";
;
PART_NUMBER"CS-2202FB01"
PACK_TYPE"0402LF"
VALUE"2.2"
TOLERANCE"1%"
MATERIAL"CHIP"
WATTAGE"1/16W"
LOCATION"PR299"
CDS_LIB"pure_quanta"
LOCATION"PR299"
$SEC"1"
CDS_SEC"1";
"A"
$PN"1"1;
"B"
$PN"2"26;
%"VCC15"
"1","(-2375,-225)","0","logical_power","I13";
;
HDL_POWER"PVCCIN_CPU1_PVCC"
CDS_LIB"logical_power";
"A"1;
%"UNIVERSAL_GND"
"1","(-2750,550)","0","logical_power","I14";
;
HDL_POWER"GND"
CDS_LIB"logical_power";
"A"10;
%"Q_RES"
"2","(-2750,775)","2","pure_quanta","I15";
;
PART_NUMBER"CS28872FB01"
WATTAGE"1/16W"
PACK_TYPE"0402LF"
VALUE"8.87K"
TOLERANCE"1%"
MATERIAL"EMPTY"
LOCATION"PR298"
CDS_LIB"pure_quanta"
LOCATION"PR298"
$SEC"1"
CDS_SEC"1";
"A"
$PN"1"29;
"B"
$PN"2"10;
%"UNIVERSAL_GND"
"1","(-1950,-775)","0","logical_power","I18";
;
HDL_POWER"GND"
CDS_LIB"logical_power";
"A"11;
%"Q_CAP"
"1","(-1950,-550)","0","pure_quanta","I19";
;
PART_NUMBER"CH5222KEB01"
PACK_TYPE"C0402"
VOLTAGE"10V"
VALUE"2.2UF"
TOLERANCE"10%"
MATERIAL"X6S"
LOCATION"PC525_P1_4"
CDS_LIB"pure_quanta"
LOCATION"PC525_P1_4"
$SEC"1"
CDS_SEC"1";
"B"
$PN"2"11;
"A"
$PN"1"1;
%"UNIVERSAL_GND"
"1","(-2875,-1825)","0","logical_power","I2";
;
HDL_POWER"GND"
CDS_LIB"logical_power";
"A"8;
%"UNIVERSAL_GND"
"1","(-2850,1000)","0","logical_power","I20";
;
HDL_POWER"GND"
CDS_LIB"logical_power";
"A"12;
%"UNIVERSAL_GND"
"1","(-2350,1525)","0","logical_power","I23";
;
HDL_POWER"GND"
CDS_LIB"logical_power";
"A"13;
%"Q_CAP"
"1","(-2350,1775)","0","pure_quanta","I24";
;
PART_NUMBER"CH5222KEB01"
PACK_TYPE"C0402"
VOLTAGE"10V"
VALUE"2.2UF"
TOLERANCE"10%"
MATERIAL"X6S"
LOCATION"PC524"
CDS_LIB"pure_quanta"
LOCATION"PC524"
$SEC"1"
CDS_SEC"1";
"B"
$PN"2"13;
"A"
$PN"1"31;
%"Q_RES"
"2","(-2350,2275)","0","pure_quanta","I25";
;
PART_NUMBER"CS-2202FB01"
WATTAGE"1/16W"
PACK_TYPE"0402LF"
VALUE"2.2"
TOLERANCE"1%"
MATERIAL"CHIP"
LOCATION"PR300"
CDS_LIB"pure_quanta"
LOCATION"PR300"
$SEC"1"
CDS_SEC"1";
"A"
$PN"1"2;
"B"
$PN"2"31;
%"VCC15"
"1","(-2350,2600)","0","logical_power","I26";
;
HDL_POWER"PVCCIN_CPU1_PVCC"
CDS_LIB"logical_power";
"A"2;
%"Q_CAP"
"2","(-2025,1075)","0","pure_quanta","I27";
;
PART_NUMBER"CH4104K1B00"
PACK_TYPE"0402"
VOLTAGE"25V"
VALUE"0.1UF"
TOLERANCE"10%"
MATERIAL"X7R"
LOCATION"PC1359"
CDS_LIB"pure_quanta"
$SEC"1"
CDS_SEC"1";
"A"
$PN"1"12;
"B"
$PN"2"46;
%"UNIVERSAL_GND"
"1","(-1925,2050)","0","logical_power","I28";
;
HDL_POWER"GND"
CDS_LIB"logical_power";
"A"14;
%"Q_CAP"
"1","(-1925,2275)","0","pure_quanta","I29";
;
PART_NUMBER"CH5222KEB01"
VOLTAGE"10V"
PACK_TYPE"C0402"
VALUE"2.2UF"
TOLERANCE"10%"
MATERIAL"X6S"
LOCATION"PC526_P1_3"
CDS_LIB"pure_quanta"
LOCATION"PC526_P1_3"
$SEC"1"
CDS_SEC"1";
"B"
$PN"2"14;
"A"
$PN"1"2;
%"Q_RES"
"2","(-2775,-2050)","2","pure_quanta","I3";
;
PART_NUMBER"CS28872FB01"
PACK_TYPE"0402LF"
VALUE"8.87K"
TOLERANCE"1%"
MATERIAL"EMPTY"
WATTAGE"1/16W"
LOCATION"PR297"
CDS_LIB"pure_quanta"
LOCATION"PR297"
$SEC"1"
CDS_SEC"1";
"A"
$PN"1"21;
"B"
$PN"2"7;
%"UNIVERSAL_GND"
"1","(-200,-2275)","0","logical_power","I30";
;
HDL_POWER"GND"
CDS_LIB"logical_power";
"A"15;
%"UNIVERSAL_GND"
"1","(-175,550)","0","logical_power","I32";
;
HDL_POWER"GND"
CDS_LIB"logical_power";
"A"16;
%"Q_CAP"
"1","(-50,-650)","0","pure_quanta","I33";
;
PART_NUMBER"TMP_QCH2336K1B12"
VOLTAGE"50V"
VALUE"3300PF"
TOLERANCE"10%"
MATERIAL"X7R"
PACK_TYPE"0402"
LOCATION"PC527_P1_4"
CDS_LIB"pure_quanta"
LOCATION"PC527_P1_4"
$SEC"1"
CDS_SEC"1";
"B"
$PN"2"17;
"A"
$PN"1"3;
%"Q_RES"
"1","(400,-1100)","0","pure_quanta","I34";
;
PART_NUMBER"CS-3302FB01"
PACK_TYPE"0402LF"
VALUE"3.3"
TOLERANCE"1%"
MATERIAL"CHIP"
WATTAGE"1/16W"
LOCATION"PR1788"
CDS_LIB"pure_quanta"
$SEC"1"
CDS_SEC"1";
"B"
$PN"2"34;
"A"
$PN"1"33;
%"Q_CAP"
"1","(350,-650)","0","pure_quanta","I35";
;
PART_NUMBER"CH5103KEB01"
PACK_TYPE"C0402"
VOLTAGE"16V"
VALUE"1UF"
TOLERANCE"10%"
MATERIAL"X6S"
LOCATION"PC529_P1_4"
CDS_LIB"pure_quanta"
LOCATION"PC529_P1_4"
$SEC"1"
CDS_SEC"1";
"B"
$PN"2"17;
"A"
$PN"1"3;
%"Q_CAP"
"1","(750,-650)","0","pure_quanta","I36";
;
PART_NUMBER"CH6223MEA01"
PACK_TYPE"C0805"
VOLTAGE"16V"
VALUE"22UF"
TOLERANCE"20%"
MATERIAL"X6S"
LOCATION"PC533_P1_4"
CDS_LIB"pure_quanta"
LOCATION"PC533_P1_4"
$SEC"1"
CDS_SEC"1";
"B"
$PN"2"17;
"A"
$PN"1"3;
%"Q_INDUCTOR4P_14"
"1","(1600,-1675)","0","pure_quanta","I37";
;
PART_NUMBER"CV+15^0TZ04"
PART_TYPE"SMLF"
MATERIAL"IND"
VALUE"150NH"
LOCATION"PL28"
NEEDS_NO_SIZE"TRUE"
CDS_LIB"pure_quanta"
SEC_TYPE""
SEC"1";
"1"
$PN"1"37;
"4"
$PN"4"5;
"3"
$PN"3"38;
"2"
$PN"2"36;
%"Q_RES"
"1","(1525,-2175)","0","pure_quanta","I38";
;
PART_NUMBER"CS00002JB13"
PACK_TYPE"0402LF"
VALUE"0"
TOLERANCE"5%"
MATERIAL"CHIP"
WATTAGE"1/16W"
LOCATION"PR301"
CDS_LIB"pure_quanta"
$SEC"1"
CDS_SEC"1";
"B"
$PN"2"5;
"A"
$PN"1"32;
%"Q_CAP"
"1","(1125,-1275)","2","pure_quanta","I39";
;
PART_NUMBER"CH4106K1B01"
PACK_TYPE"C0402"
VOLTAGE"50V"
VALUE"100NF"
TOLERANCE"10%"
MATERIAL"X7R"
LOCATION"PC531"
CDS_LIB"pure_quanta"
$SEC"1"
CDS_SEC"1";
"B"
$PN"2"35;
"A"
$PN"1"34;
%"Q_CAP"
"1","(1150,-650)","0","pure_quanta","I41";
;
PART_NUMBER"CH6223MEA01"
PACK_TYPE"C0805"
VOLTAGE"16V"
VALUE"22UF"
TOLERANCE"20%"
MATERIAL"X6S"
LOCATION"PC535_P1_4"
CDS_LIB"pure_quanta"
LOCATION"PC535_P1_4"
$SEC"1"
CDS_SEC"1";
"B"
$PN"2"17;
"A"
$PN"1"3;
%"Q_CAP"
"1","(1525,-650)","0","pure_quanta","I42";
;
PART_NUMBER"CH6223MEA01"
PACK_TYPE"C0805"
VOLTAGE"16V"
VALUE"22UF"
TOLERANCE"20%"
MATERIAL"X6S"
LOCATION"PC537_P1_4"
CDS_LIB"pure_quanta"
LOCATION"PC537_P1_4"
$SEC"1"
CDS_SEC"1";
"B"
$PN"2"17;
"A"
$PN"1"3;
%"UNIVERSAL_GND"
"1","(1750,-1075)","0","logical_power","I43";
;
HDL_POWER"GND"
CDS_LIB"logical_power";
"A"17;
%"VCC15"
"1","(1750,-275)","0","logical_power","I44";
;
HDL_POWER"SW_P12V_PVCCIN_CPU1_FLT"
CDS_LIB"logical_power";
"A"3;
%"Q_RES"
"1","(1575,650)","0","pure_quanta","I45";
;
PART_NUMBER"CS00002JB13"
PACK_TYPE"0402LF"
MATERIAL"CHIP"
VALUE"0"
TOLERANCE"5%"
WATTAGE"1/16W"
LOCATION"PR302"
CDS_LIB"pure_quanta"
$SEC"1"
CDS_SEC"1";
"B"
$PN"2"6;
"A"
$PN"1"39;
%"Q_RES"
"1","(425,1725)","0","pure_quanta","I46";
;
PART_NUMBER"CS-3302FB01"
WATTAGE"1/16W"
PACK_TYPE"0402LF"
VALUE"3.3"
TOLERANCE"1%"
MATERIAL"CHIP"
LOCATION"PR1789"
CDS_LIB"pure_quanta"
$SEC"1"
CDS_SEC"1";
"B"
$PN"2"41;
"A"
$PN"1"40;
%"Q_CAP"
"1","(-25,2175)","0","pure_quanta","I48";
;
PART_NUMBER"TMP_QCH2336K1B12"
PACK_TYPE"0402"
VOLTAGE"50V"
VALUE"3300PF"
TOLERANCE"10%"
MATERIAL"X7R"
LOCATION"PC528_P1_3"
CDS_LIB"pure_quanta"
LOCATION"PC528_P1_3"
$SEC"1"
CDS_SEC"1";
"B"
$PN"2"18;
"A"
$PN"1"4;
%"Q_CAP"
"1","(375,2175)","0","pure_quanta","I49";
;
PART_NUMBER"CH5103KEB01"
VOLTAGE"16V"
TOLERANCE"10%"
PACK_TYPE"C0402"
VALUE"1UF"
MATERIAL"X6S"
LOCATION"PC530_P1_3"
CDS_LIB"pure_quanta"
LOCATION"PC530_P1_3"
$SEC"1"
CDS_SEC"1";
"B"
$PN"2"18;
"A"
$PN"1"4;
%"Q_CAP"
"1","(775,2175)","0","pure_quanta","I50";
;
PART_NUMBER"CH6223MEA01"
MATERIAL"X6S"
VOLTAGE"16V"
PACK_TYPE"C0805"
VALUE"22UF"
TOLERANCE"20%"
LOCATION"PC534_P1_3"
CDS_LIB"pure_quanta"
LOCATION"PC534_P1_3"
$SEC"1"
CDS_SEC"1";
"B"
$PN"2"18;
"A"
$PN"1"4;
%"Q_INDUCTOR4P_14"
"1","(1625,1150)","0","pure_quanta","I51";
;
PART_NUMBER"CV+15^0TZ04"
MATERIAL"IND"
VALUE"150NH"
PART_TYPE"SMLF"
LOCATION"PL29"
SEC_TYPE""
CDS_LIB"pure_quanta"
NEEDS_NO_SIZE"TRUE"
SEC"1";
"1"
$PN"1"44;
"4"
$PN"4"6;
"3"
$PN"3"45;
"2"
$PN"2"42;
%"Q_CAP"
"1","(1150,1550)","2","pure_quanta","I52";
;
PART_NUMBER"CH4106K1B01"
PACK_TYPE"C0402"
VOLTAGE"50V"
VALUE"100NF"
TOLERANCE"10%"
MATERIAL"X7R"
LOCATION"PC532"
CDS_LIB"pure_quanta"
$SEC"1"
CDS_SEC"1";
"B"
$PN"2"43;
"A"
$PN"1"41;
%"UNIVERSAL_GND"
"1","(1775,1750)","0","logical_power","I53";
;
HDL_POWER"GND"
CDS_LIB"logical_power";
"A"18;
%"Q_CAP"
"1","(1175,2175)","0","pure_quanta","I54";
;
PART_NUMBER"CH6223MEA01"
PACK_TYPE"C0805"
VOLTAGE"16V"
VALUE"22UF"
TOLERANCE"20%"
MATERIAL"X6S"
LOCATION"PC536_P1_3"
CDS_LIB"pure_quanta"
LOCATION"PC536_P1_3"
$SEC"1"
CDS_SEC"1";
"B"
$PN"2"18;
"A"
$PN"1"4;
%"Q_CAP"
"1","(1550,2175)","0","pure_quanta","I55";
;
PART_NUMBER"CH6223MEA01"
PACK_TYPE"C0805"
VOLTAGE"16V"
VALUE"22UF"
TOLERANCE"20%"
MATERIAL"X6S"
LOCATION"PC538_P1_3"
CDS_LIB"pure_quanta"
LOCATION"PC538_P1_3"
$SEC"1"
CDS_SEC"1";
"B"
$PN"2"18;
"A"
$PN"1"4;
%"VCC15"
"1","(1775,2550)","0","logical_power","I56";
;
HDL_POWER"SW_P12V_PVCCIN_CPU1_FLT"
CDS_LIB"logical_power";
"A"4;
%"Q_CAP"
"1","(3325,-1750)","0","pure_quanta","I58";
;
PART_NUMBER"CH622KMEA03"
PACK_TYPE"C0805"
MATERIAL"X6S"
TOLERANCE"20%"
VALUE"22UF"
VOLTAGE"4V"
LOCATION"PC541_P1_4"
CDS_LIB"pure_quanta"
LOCATION"PC541_P1_4"
$SEC"1"
CDS_SEC"1";
"B"
$PN"2"19;
"A"
$PN"1"5;
%"Q_CAP"
"1","(3750,-1750)","0","pure_quanta","I59";
;
PART_NUMBER"CH622KMEA03"
PACK_TYPE"C0805"
MATERIAL"X6S"
TOLERANCE"20%"
VALUE"22UF"
VOLTAGE"4V"
LOCATION"PC543_P1_4"
CDS_LIB"pure_quanta"
LOCATION"PC543_P1_4"
$SEC"1"
CDS_SEC"1";
"B"
$PN"2"19;
"A"
$PN"1"5;
%"Q_CAP"
"2","(-2050,-1750)","0","pure_quanta","I6";
;
PART_NUMBER"CH4104K1B00"
PACK_TYPE"0402"
VOLTAGE"25V"
VALUE"0.1UF"
TOLERANCE"10%"
MATERIAL"X7R"
LOCATION"PC1358"
CDS_LIB"pure_quanta"
$SEC"1"
CDS_SEC"1";
"A"
$PN"1"8;
"B"
$PN"2"25;
%"UNIVERSAL_GND"
"1","(4050,-2125)","0","logical_power","I60";
;
HDL_POWER"GND"
CDS_LIB"logical_power";
"A"19;
%"VCC15"
"1","(4050,-1350)","0","logical_power","I61";
;
HDL_POWER"PVCCIN_CPU1"
CDS_LIB"logical_power";
"A"5;
%"UNIVERSAL_GND"
"1","(4200,700)","0","logical_power","I62";
;
HDL_POWER"GND"
CDS_LIB"logical_power";
"A"20;
%"Q_CAP"
"1","(3475,1075)","0","pure_quanta","I63";
;
PART_NUMBER"CH622KMEA03"
PACK_TYPE"C0805"
TOLERANCE"20%"
MATERIAL"X6S"
VALUE"22UF"
VOLTAGE"4V"
LOCATION"PC542_P1_3"
CDS_LIB"pure_quanta"
LOCATION"PC542_P1_3"
$SEC"1"
CDS_SEC"1";
"B"
$PN"2"20;
"A"
$PN"1"6;
%"Q_CAP"
"1","(3900,1075)","0","pure_quanta","I64";
;
PART_NUMBER"CH622KMEA03"
PACK_TYPE"C0805"
MATERIAL"X6S"
TOLERANCE"20%"
VALUE"22UF"
VOLTAGE"4V"
LOCATION"PC544_P1_3"
CDS_LIB"pure_quanta"
LOCATION"PC544_P1_3"
$SEC"1"
CDS_SEC"1";
"B"
$PN"2"20;
"A"
$PN"1"6;
%"VCC15"
"1","(4200,1475)","0","logical_power","I65";
;
HDL_POWER"PVCCIN_CPU1"
CDS_LIB"logical_power";
"A"6;
%"ISL99390FRZTR5935"
"1","(-825,1275)","0","pure_quanta","I66";
;
PART_NUMBER"AL099390004"
VALUE"ISL99390FRZ-TR5935"
MATERIAL"IC"
PART_TYPE"SMLF"
LOCATION"PU28_P1_3"
NEEDS_NO_SIZE"TRUE"
CDS_LMAN_SYM_OUTLINE"-300,700,250,-650"
CDS_LIB"pure_quanta"
$SEC"1"
CDS_SEC"1";
"PGND2"
$PN"7_9-20_24"16;
"GL2"
$PN"41"0;
"GL1"
$PN"6"0;
"DNC"
$PN"31"0;
"EN"
$PN"35"31;
"PGND3"
$PN"40"16;
"VOS"
$PN"1"39;
"VIN2"
$PN"30"4;
"PGND1"
$PN"5"16;
"SW"
$PN"10_19"44;
"LSET"
$PN"37"29;
"IOUT"
$PN"38"30;
"TOUT_FLT"
$PN"36"28;
"PVCC"
$PN"4"2;
"PHASE"
$PN"32"43;
"VIN1"
$PN"25_29"4;
"BOOT"
$PN"33"40;
"AGND"
$PN"2"16;
"VCC"
$PN"3"31;
"REFIN"
$PN"39"46;
"PWM"
$PN"34"27;
%"UNIVERSAL_GND"
"1","(-2375,-1300)","0","logical_power","I9";
;
HDL_POWER"GND"
CDS_LIB"logical_power";
"A"9;
END.
